(kicad_pcb
	(version 20260206)
	(generator "pcbnew")
	(generator_version "10.0")
	(general
		(thickness 1.6)
		(legacy_teardrops no)
	)
	(paper "A4")
	(title_block
		(title "04192023_DAF0TMB3IC0_F0TG_MB_C_brd_V02_OCP.brd")
		(comment 1 "Grand Teton / footprint 2783 of 8354 (U26), pads 3116-3227 of 6102")
	)
	(layers
		(0 "F.Cu" signal "TOP")
		(4 "In1.Cu" signal "GND")
		(6 "In2.Cu" signal "IN1")
		(8 "In3.Cu" signal "GND1")
		(10 "In4.Cu" signal "IN2")
		(12 "In5.Cu" signal "GND2")
		(14 "In6.Cu" signal "IN3")
		(16 "In7.Cu" signal "GND3")
		(18 "In8.Cu" signal "VCC")
		(20 "In9.Cu" signal "VCC1")
		(22 "In10.Cu" signal "GND4")
		(24 "In11.Cu" signal "IN4")
		(26 "In12.Cu" signal "GND5")
		(28 "In13.Cu" signal "IN5")
		(30 "In14.Cu" signal "GND6")
		(32 "In15.Cu" signal "IN6")
		(34 "In16.Cu" signal "GND7")
		(2 "B.Cu" signal "BOTTOM")
		(9 "F.Adhes" user "F.Adhesive")
		(11 "B.Adhes" user "B.Adhesive")
		(13 "F.Paste" user "Package Geometry/Pastemask Top")
		(15 "B.Paste" user "Package Geometry/Pastemask Bottom")
		(5 "F.SilkS" user "Ref Des/Silkscreen Top")
		(7 "B.SilkS" user "Ref Des/Silkscreen Bottom")
		(1 "F.Mask" user "Board Geometry/Soldermask Top")
		(3 "B.Mask" user "Board Geometry/Soldermask Bottom")
		(17 "Dwgs.User" user "User.Drawings")
		(19 "Cmts.User" user "User.Comments")
		(21 "Eco1.User" user "User.Eco1")
		(23 "Eco2.User" user "User.Eco2")
		(25 "Edge.Cuts" user "Board Geometry/Outline")
		(27 "Margin" user)
		(31 "F.CrtYd" user "Package Geometry/Place Bound Top")
		(29 "B.CrtYd" user "Package Geometry/Place Bound Bottom")
		(35 "F.Fab" user "Ref Des/Assembly Top")
		(33 "B.Fab" user "Ref Des/Assembly Bottom")
	)
	(footprint ""
		(layer "F.Cu")
		(at 111.927894 -258.880356 180)
		(property "Reference" "U26"
			(at -45.05579 -61.794136 0)
			(unlocked yes)
			(layer "F.SilkS")
			(effects
				(font
					(size 0.7874 0.5842)
					(thickness 0.1524)
				)
			)
		)
		(property "Value" ""
			(at 0 0 180)
			(layer "F.Fab")
			(effects
				(font
					(size 1.27 1.27)
				)
			)
		)
		(duplicate_pad_numbers_are_jumpers no)
		(pad "CE20" smd circle
			(at -16.599916 17.370044 180)
			(size 0.450088 0.450088)
			(layers "F.Cu" "F.Mask" "F.Paste")
			(net "GND")
		)
		(pad "CE21" smd circle
			(at -15.660116 17.370044 180)
			(size 0.450088 0.450088)
			(layers "F.Cu" "F.Mask" "F.Paste")
			(net "M_I_CPU1_SB_DQS_DN<5>")
		)
		(pad "CE22" smd circle
			(at -14.720062 17.370044 180)
			(size 0.450088 0.450088)
			(layers "F.Cu" "F.Mask" "F.Paste")
			(net "GND")
		)
		(pad "CE23" smd circle
			(at -13.780008 17.370044 180)
			(size 0.450088 0.450088)
			(layers "F.Cu" "F.Mask" "F.Paste")
			(net "P5E_CPU1_P3_TX_DN<15>")
		)
		(pad "CE24" smd circle
			(at -12.839954 17.370044 180)
			(size 0.450088 0.450088)
			(layers "F.Cu" "F.Mask" "F.Paste")
			(net "P5E_CPU1_P3_TX_DP<15>")
		)
		(pad "CE25" smd circle
			(at -11.8999 17.370044 180)
			(size 0.450088 0.450088)
			(layers "F.Cu" "F.Mask" "F.Paste")
			(net "GND")
		)
		(pad "CE26" smd circle
			(at -10.9601 17.370044 180)
			(size 0.450088 0.450088)
			(layers "F.Cu" "F.Mask" "F.Paste")
			(net "P5E_CPU1_P3_TX_DN<12>")
		)
		(pad "CE27" smd circle
			(at -10.020046 17.370044 180)
			(size 0.450088 0.450088)
			(layers "F.Cu" "F.Mask" "F.Paste")
			(net "P5E_CPU1_P3_TX_DP<12>")
		)
		(pad "CE28" smd circle
			(at -9.079992 17.370044 180)
			(size 0.450088 0.450088)
			(layers "F.Cu" "F.Mask" "F.Paste")
			(net "GND")
		)
		(pad "CE29" smd circle
			(at -8.139938 17.370044 180)
			(size 0.450088 0.450088)
			(layers "F.Cu" "F.Mask" "F.Paste")
			(net "P5E_CPU1_P3_TX_DN<9>")
		)
		(pad "CE30" smd circle
			(at -7.199884 17.370044 180)
			(size 0.450088 0.450088)
			(layers "F.Cu" "F.Mask" "F.Paste")
			(net "P5E_CPU1_P3_TX_DP<9>")
		)
		(pad "CE31" smd circle
			(at -6.260084 17.370044 180)
			(size 0.450088 0.450088)
			(layers "F.Cu" "F.Mask" "F.Paste")
			(net "GND")
		)
		(pad "CE32" smd circle
			(at -5.32003 17.370044 180)
			(size 0.450088 0.450088)
			(layers "F.Cu" "F.Mask" "F.Paste")
			(net "P5E_CPU1_P3_TX_DN<6>")
		)
		(pad "CE33" smd circle
			(at -4.379976 17.370044 180)
			(size 0.450088 0.450088)
			(layers "F.Cu" "F.Mask" "F.Paste")
			(net "P5E_CPU1_P3_TX_DP<6>")
		)
		(pad "CE34" smd circle
			(at -3.439922 17.370044 180)
			(size 0.450088 0.450088)
			(layers "F.Cu" "F.Mask" "F.Paste")
			(net "GND")
		)
		(pad "CE35" smd circle
			(at -2.500122 17.370044 180)
			(size 0.450088 0.450088)
			(layers "F.Cu" "F.Mask" "F.Paste")
			(net "GND")
		)
		(pad "CE36" smd circle
			(at -1.560068 17.370044 180)
			(size 0.450088 0.450088)
			(layers "F.Cu" "F.Mask" "F.Paste")
			(net "GND")
		)
		(pad "CE40" smd circle
			(at 1.260094 17.370044 180)
			(size 0.450088 0.450088)
			(layers "F.Cu" "F.Mask" "F.Paste")
			(net "GND")
		)
		(pad "CE41" smd circle
			(at 2.199894 17.370044 180)
			(size 0.450088 0.450088)
			(layers "F.Cu" "F.Mask" "F.Paste")
			(net "GND")
		)
		(pad "CE42" smd circle
			(at 3.139948 17.370044 180)
			(size 0.450088 0.450088)
			(layers "F.Cu" "F.Mask" "F.Paste")
			(net "GND")
		)
		(pad "CE43" smd circle
			(at 4.080002 17.370044 180)
			(size 0.450088 0.450088)
			(layers "F.Cu" "F.Mask" "F.Paste")
			(net "P5E_CPU1_P1_RX_DP<9>")
		)
		(pad "CE44" smd circle
			(at 5.020056 17.370044 180)
			(size 0.450088 0.450088)
			(layers "F.Cu" "F.Mask" "F.Paste")
			(net "P5E_CPU1_P1_RX_DN<9>")
		)
		(pad "CE45" smd circle
			(at 5.96011 17.370044 180)
			(size 0.450088 0.450088)
			(layers "F.Cu" "F.Mask" "F.Paste")
			(net "GND")
		)
		(pad "CE46" smd circle
			(at 6.89991 17.370044 180)
			(size 0.450088 0.450088)
			(layers "F.Cu" "F.Mask" "F.Paste")
			(net "P5E_CPU1_P1_RX_DP<6>")
		)
		(pad "CE47" smd circle
			(at 7.839964 17.370044 180)
			(size 0.450088 0.450088)
			(layers "F.Cu" "F.Mask" "F.Paste")
			(net "P5E_CPU1_P1_RX_DN<6>")
		)
		(pad "CE48" smd circle
			(at 8.780018 17.370044 180)
			(size 0.450088 0.450088)
			(layers "F.Cu" "F.Mask" "F.Paste")
			(net "GND")
		)
		(pad "CE49" smd circle
			(at 9.720072 17.370044 180)
			(size 0.450088 0.450088)
			(layers "F.Cu" "F.Mask" "F.Paste")
			(net "P5E_CPU1_P1_RX_DP<3>")
		)
		(pad "CE50" smd circle
			(at 10.659872 17.370044 180)
			(size 0.450088 0.450088)
			(layers "F.Cu" "F.Mask" "F.Paste")
			(net "P5E_CPU1_P1_RX_DN<3>")
		)
		(pad "CE51" smd circle
			(at 11.599926 17.370044 180)
			(size 0.450088 0.450088)
			(layers "F.Cu" "F.Mask" "F.Paste")
			(net "GND")
		)
		(pad "CE52" smd circle
			(at 12.53998 17.370044 180)
			(size 0.450088 0.450088)
			(layers "F.Cu" "F.Mask" "F.Paste")
			(net "P5E_CPU1_P1_RX_DP<0>")
		)
		(pad "CE53" smd circle
			(at 13.480034 17.370044 180)
			(size 0.450088 0.450088)
			(layers "F.Cu" "F.Mask" "F.Paste")
			(net "P5E_CPU1_P1_RX_DN<0>")
		)
		(pad "CE54" smd circle
			(at 14.420088 17.370044 180)
			(size 0.450088 0.450088)
			(layers "F.Cu" "F.Mask" "F.Paste")
			(net "GND")
		)
		(pad "CE55" smd circle
			(at 15.359888 17.370044 180)
			(size 0.450088 0.450088)
			(layers "F.Cu" "F.Mask" "F.Paste")
			(net "M_C_CPU1_SB_DQS_DN<5>")
		)
		(pad "CE56" smd circle
			(at 16.299942 17.370044 180)
			(size 0.450088 0.450088)
			(layers "F.Cu" "F.Mask" "F.Paste")
			(net "GND")
		)
		(pad "CE57" smd circle
			(at 17.239996 17.370044 180)
			(size 0.450088 0.450088)
			(layers "F.Cu" "F.Mask" "F.Paste")
			(net "M_C_CPU1_SB_DQS_DN<0>")
		)
		(pad "CE58" smd circle
			(at 18.18005 17.370044 180)
			(size 0.450088 0.450088)
			(layers "F.Cu" "F.Mask" "F.Paste")
			(net "GND")
		)
		(pad "CE59" smd circle
			(at 19.120104 17.370044 180)
			(size 0.450088 0.450088)
			(layers "F.Cu" "F.Mask" "F.Paste")
			(net "M_D_CPU1_SB_DQS_DN<5>")
		)
		(pad "CE60" smd circle
			(at 20.059904 17.370044 180)
			(size 0.450088 0.450088)
			(layers "F.Cu" "F.Mask" "F.Paste")
			(net "M_D_CPU1_SB_DQS_DN<0>")
		)
		(pad "CE61" smd circle
			(at 20.999958 17.370044 180)
			(size 0.450088 0.450088)
			(layers "F.Cu" "F.Mask" "F.Paste")
			(net "GND")
		)
		(pad "CE62" smd circle
			(at 21.940012 17.370044 180)
			(size 0.450088 0.450088)
			(layers "F.Cu" "F.Mask" "F.Paste")
			(net "M_B_CPU1_SB_DQS_DN<5>")
		)
		(pad "CE63" smd circle
			(at 22.880066 17.370044 180)
			(size 0.450088 0.450088)
			(layers "F.Cu" "F.Mask" "F.Paste")
			(net "GND")
		)
		(pad "CE64" smd circle
			(at 23.82012 17.370044 180)
			(size 0.450088 0.450088)
			(layers "F.Cu" "F.Mask" "F.Paste")
			(net "M_B_CPU1_SB_DQS_DN<0>")
		)
		(pad "CE65" smd circle
			(at 24.75992 17.370044 180)
			(size 0.450088 0.450088)
			(layers "F.Cu" "F.Mask" "F.Paste")
			(net "GND")
		)
		(pad "CE66" smd circle
			(at 25.699974 17.370044 180)
			(size 0.450088 0.450088)
			(layers "F.Cu" "F.Mask" "F.Paste")
			(net "M_F_CPU1_SB_DQS_DN<5>")
		)
		(pad "CE67" smd circle
			(at 26.640028 17.370044 180)
			(size 0.450088 0.450088)
			(layers "F.Cu" "F.Mask" "F.Paste")
			(net "M_F_CPU1_SB_DQS_DN<0>")
		)
		(pad "CE68" smd circle
			(at 27.580082 17.370044 180)
			(size 0.450088 0.450088)
			(layers "F.Cu" "F.Mask" "F.Paste")
			(net "GND")
		)
		(pad "CE69" smd circle
			(at 28.519882 17.370044 180)
			(size 0.450088 0.450088)
			(layers "F.Cu" "F.Mask" "F.Paste")
			(net "M_E_CPU1_SB_DQS_DN<5>")
		)
		(pad "CE70" smd circle
			(at 29.459936 17.370044 180)
			(size 0.450088 0.450088)
			(layers "F.Cu" "F.Mask" "F.Paste")
			(net "GND")
		)
		(pad "CE71" smd circle
			(at 30.39999 17.370044 180)
			(size 0.450088 0.450088)
			(layers "F.Cu" "F.Mask" "F.Paste")
			(net "M_E_CPU1_SB_DQS_DN<0>")
		)
		(pad "CE72" smd circle
			(at 31.340044 17.370044 180)
			(size 0.450088 0.450088)
			(layers "F.Cu" "F.Mask" "F.Paste")
			(net "GND")
		)
		(pad "CE73" smd circle
			(at 32.280098 17.370044 180)
			(size 0.450088 0.450088)
			(layers "F.Cu" "F.Mask" "F.Paste")
			(net "M_A_CPU1_SB_DQS_DN<5>")
		)
		(pad "CE74" smd circle
			(at 33.219898 17.370044 180)
			(size 0.450088 0.450088)
			(layers "F.Cu" "F.Mask" "F.Paste")
			(net "M_A_CPU1_SB_DQS_DN<0>")
		)
		(pad "CE75" smd circle
			(at 34.159952 17.370044 180)
			(size 0.450088 0.450088)
			(layers "F.Cu" "F.Mask" "F.Paste")
			(net "GND")
		)
		(pad "CF2" smd circle
			(at -33.990026 18.18005 180)
			(size 0.450088 0.450088)
			(layers "F.Cu" "F.Mask" "F.Paste")
			(net "M_G_CPU1_SB_DQ<4>")
		)
		(pad "CF3" smd circle
			(at -33.049972 18.18005 180)
			(size 0.450088 0.450088)
			(layers "F.Cu" "F.Mask" "F.Paste")
			(net "GND")
		)
		(pad "CF4" smd circle
			(at -32.109918 18.18005 180)
			(size 0.450088 0.450088)
			(layers "F.Cu" "F.Mask" "F.Paste")
			(net "M_G_CPU1_SB_DQS_DP<5>")
		)
		(pad "CF5" smd circle
			(at -31.170118 18.18005 180)
			(size 0.450088 0.450088)
			(layers "F.Cu" "F.Mask" "F.Paste")
			(net "GND")
		)
		(pad "CF6" smd circle
			(at -30.230064 18.18005 180)
			(size 0.450088 0.450088)
			(layers "F.Cu" "F.Mask" "F.Paste")
			(net "M_K_CPU1_SB_DQ<4>")
		)
		(pad "CF7" smd circle
			(at -29.29001 18.18005 180)
			(size 0.450088 0.450088)
			(layers "F.Cu" "F.Mask" "F.Paste")
			(net "M_K_CPU1_SB_DQS_DP<5>")
		)
		(pad "CF8" smd circle
			(at -28.349956 18.18005 180)
			(size 0.450088 0.450088)
			(layers "F.Cu" "F.Mask" "F.Paste")
			(net "GND")
		)
		(pad "CF9" smd circle
			(at -27.409902 18.18005 180)
			(size 0.450088 0.450088)
			(layers "F.Cu" "F.Mask" "F.Paste")
			(net "M_L_CPU1_SB_DQ<4>")
		)
		(pad "CF10" smd circle
			(at -26.470102 18.18005 180)
			(size 0.450088 0.450088)
			(layers "F.Cu" "F.Mask" "F.Paste")
			(net "GND")
		)
		(pad "CF11" smd circle
			(at -25.530048 18.18005 180)
			(size 0.450088 0.450088)
			(layers "F.Cu" "F.Mask" "F.Paste")
			(net "M_L_CPU1_SB_DQS_DP<5>")
		)
		(pad "CF12" smd circle
			(at -24.589994 18.18005 180)
			(size 0.450088 0.450088)
			(layers "F.Cu" "F.Mask" "F.Paste")
			(net "GND")
		)
		(pad "CF13" smd circle
			(at -23.64994 18.18005 180)
			(size 0.450088 0.450088)
			(layers "F.Cu" "F.Mask" "F.Paste")
			(net "M_H_CPU1_SB_DQ<4>")
		)
		(pad "CF14" smd circle
			(at -22.709886 18.18005 180)
			(size 0.450088 0.450088)
			(layers "F.Cu" "F.Mask" "F.Paste")
			(net "M_H_CPU1_SB_DQS_DP<5>")
		)
		(pad "CF15" smd circle
			(at -21.770086 18.18005 180)
			(size 0.450088 0.450088)
			(layers "F.Cu" "F.Mask" "F.Paste")
			(net "GND")
		)
		(pad "CF16" smd circle
			(at -20.830032 18.18005 180)
			(size 0.450088 0.450088)
			(layers "F.Cu" "F.Mask" "F.Paste")
			(net "M_J_CPU1_SB_DQ<4>")
		)
		(pad "CF17" smd circle
			(at -19.889978 18.18005 180)
			(size 0.450088 0.450088)
			(layers "F.Cu" "F.Mask" "F.Paste")
			(net "GND")
		)
		(pad "CF18" smd circle
			(at -18.949924 18.18005 180)
			(size 0.450088 0.450088)
			(layers "F.Cu" "F.Mask" "F.Paste")
			(net "M_J_CPU1_SB_DQS_DP<5>")
		)
		(pad "CF19" smd circle
			(at -18.010124 18.18005 180)
			(size 0.450088 0.450088)
			(layers "F.Cu" "F.Mask" "F.Paste")
			(net "GND")
		)
		(pad "CF20" smd circle
			(at -17.07007 18.18005 180)
			(size 0.450088 0.450088)
			(layers "F.Cu" "F.Mask" "F.Paste")
			(net "M_I_CPU1_SB_DQ<4>")
		)
		(pad "CF21" smd circle
			(at -16.130016 18.18005 180)
			(size 0.450088 0.450088)
			(layers "F.Cu" "F.Mask" "F.Paste")
			(net "M_I_CPU1_SB_DQS_DP<5>")
		)
		(pad "CF22" smd circle
			(at -15.189962 18.18005 180)
			(size 0.450088 0.450088)
			(layers "F.Cu" "F.Mask" "F.Paste")
			(net "PVDD11_S3_P1")
		)
		(pad "CF23" smd circle
			(at -14.249908 18.18005 180)
			(size 0.450088 0.450088)
			(layers "F.Cu" "F.Mask" "F.Paste")
			(net "GND")
		)
		(pad "CF24" smd circle
			(at -13.310108 18.18005 180)
			(size 0.450088 0.450088)
			(layers "F.Cu" "F.Mask" "F.Paste")
			(net "GND")
		)
		(pad "CF25" smd circle
			(at -12.370054 18.18005 180)
			(size 0.450088 0.450088)
			(layers "F.Cu" "F.Mask" "F.Paste")
			(net "GND")
		)
		(pad "CF26" smd circle
			(at -11.43 18.18005 180)
			(size 0.450088 0.450088)
			(layers "F.Cu" "F.Mask" "F.Paste")
			(net "GND")
		)
		(pad "CF27" smd circle
			(at -10.489946 18.18005 180)
			(size 0.450088 0.450088)
			(layers "F.Cu" "F.Mask" "F.Paste")
			(net "GND")
		)
		(pad "CF28" smd circle
			(at -9.549892 18.18005 180)
			(size 0.450088 0.450088)
			(layers "F.Cu" "F.Mask" "F.Paste")
			(net "GND")
		)
		(pad "CF29" smd circle
			(at -8.610092 18.18005 180)
			(size 0.450088 0.450088)
			(layers "F.Cu" "F.Mask" "F.Paste")
			(net "GND")
		)
		(pad "CF30" smd circle
			(at -7.670038 18.18005 180)
			(size 0.450088 0.450088)
			(layers "F.Cu" "F.Mask" "F.Paste")
			(net "GND")
		)
		(pad "CF31" smd circle
			(at -6.729984 18.18005 180)
			(size 0.450088 0.450088)
			(layers "F.Cu" "F.Mask" "F.Paste")
			(net "GND")
		)
		(pad "CF32" smd circle
			(at -5.78993 18.18005 180)
			(size 0.450088 0.450088)
			(layers "F.Cu" "F.Mask" "F.Paste")
			(net "GND")
		)
		(pad "CF33" smd circle
			(at -4.849876 18.18005 180)
			(size 0.450088 0.450088)
			(layers "F.Cu" "F.Mask" "F.Paste")
			(net "GND")
		)
		(pad "CF34" smd circle
			(at -3.910076 18.18005 180)
			(size 0.450088 0.450088)
			(layers "F.Cu" "F.Mask" "F.Paste")
			(net "GND")
		)
		(pad "CF35" smd circle
			(at -2.970022 18.18005 180)
			(size 0.450088 0.450088)
			(layers "F.Cu" "F.Mask" "F.Paste")
			(net "P5E_CPU1_P3_TX_DN<1>")
		)
		(pad "CF36" smd circle
			(at -2.029968 18.18005 180)
			(size 0.450088 0.450088)
			(layers "F.Cu" "F.Mask" "F.Paste")
			(net "P5E_CPU1_P3_TX_DP<1>")
		)
		(pad "CF37" smd circle
			(at -1.089914 18.18005 180)
			(size 0.450088 0.450088)
			(layers "F.Cu" "F.Mask" "F.Paste")
			(net "GND")
		)
		(pad "CF39" smd circle
			(at 0.78994 18.18005 180)
			(size 0.450088 0.450088)
			(layers "F.Cu" "F.Mask" "F.Paste")
			(net "GND")
		)
		(pad "CF40" smd circle
			(at 1.729994 18.18005 180)
			(size 0.450088 0.450088)
			(layers "F.Cu" "F.Mask" "F.Paste")
			(net "P5E_CPU1_P1_RX_DP<14>")
		)
		(pad "CF41" smd circle
			(at 2.670048 18.18005 180)
			(size 0.450088 0.450088)
			(layers "F.Cu" "F.Mask" "F.Paste")
			(net "P5E_CPU1_P1_RX_DN<14>")
		)
		(pad "CF42" smd circle
			(at 3.610102 18.18005 180)
			(size 0.450088 0.450088)
			(layers "F.Cu" "F.Mask" "F.Paste")
			(net "GND")
		)
		(pad "CF43" smd circle
			(at 4.549902 18.18005 180)
			(size 0.450088 0.450088)
			(layers "F.Cu" "F.Mask" "F.Paste")
			(net "GND")
		)
		(pad "CF44" smd circle
			(at 5.489956 18.18005 180)
			(size 0.450088 0.450088)
			(layers "F.Cu" "F.Mask" "F.Paste")
			(net "GND")
		)
		(pad "CF45" smd circle
			(at 6.43001 18.18005 180)
			(size 0.450088 0.450088)
			(layers "F.Cu" "F.Mask" "F.Paste")
			(net "GND")
		)
		(pad "CF46" smd circle
			(at 7.370064 18.18005 180)
			(size 0.450088 0.450088)
			(layers "F.Cu" "F.Mask" "F.Paste")
			(net "GND")
		)
		(pad "CF47" smd circle
			(at 8.310118 18.18005 180)
			(size 0.450088 0.450088)
			(layers "F.Cu" "F.Mask" "F.Paste")
			(net "GND")
		)
		(pad "CF48" smd circle
			(at 9.249918 18.18005 180)
			(size 0.450088 0.450088)
			(layers "F.Cu" "F.Mask" "F.Paste")
			(net "GND")
		)
		(pad "CF49" smd circle
			(at 10.189972 18.18005 180)
			(size 0.450088 0.450088)
			(layers "F.Cu" "F.Mask" "F.Paste")
			(net "GND")
		)
		(pad "CF50" smd circle
			(at 11.130026 18.18005 180)
			(size 0.450088 0.450088)
			(layers "F.Cu" "F.Mask" "F.Paste")
			(net "GND")
		)
		(pad "CF51" smd circle
			(at 12.07008 18.18005 180)
			(size 0.450088 0.450088)
			(layers "F.Cu" "F.Mask" "F.Paste")
			(net "GND")
		)
		(pad "CF52" smd circle
			(at 13.00988 18.18005 180)
			(size 0.450088 0.450088)
			(layers "F.Cu" "F.Mask" "F.Paste")
			(net "GND")
		)
		(pad "CF53" smd circle
			(at 13.949934 18.18005 180)
			(size 0.450088 0.450088)
			(layers "F.Cu" "F.Mask" "F.Paste")
			(net "GND")
		)
		(pad "CF54" smd circle
			(at 14.889988 18.18005 180)
			(size 0.450088 0.450088)
			(layers "F.Cu" "F.Mask" "F.Paste")
			(net "PVDDIO_P1")
		)
		(pad "CF55" smd circle
			(at 15.830042 18.18005 180)
			(size 0.450088 0.450088)
			(layers "F.Cu" "F.Mask" "F.Paste")
			(net "M_C_CPU1_SB_DQS_DP<5>")
		)
		(pad "CF56" smd circle
			(at 16.770096 18.18005 180)
			(size 0.450088 0.450088)
			(layers "F.Cu" "F.Mask" "F.Paste")
			(net "M_C_CPU1_SB_DQ<4>")
		)
		(pad "CF57" smd circle
			(at 17.709896 18.18005 180)
			(size 0.450088 0.450088)
			(layers "F.Cu" "F.Mask" "F.Paste")
			(net "GND")
		)
		(pad "CF58" smd circle
			(at 18.64995 18.18005 180)
			(size 0.450088 0.450088)
			(layers "F.Cu" "F.Mask" "F.Paste")
			(net "M_D_CPU1_SB_DQS_DP<5>")
		)
		(pad "CF59" smd circle
			(at 19.590004 18.18005 180)
			(size 0.450088 0.450088)
			(layers "F.Cu" "F.Mask" "F.Paste")
			(net "GND")
		)
		(pad "CF60" smd circle
			(at 20.530058 18.18005 180)
			(size 0.450088 0.450088)
			(layers "F.Cu" "F.Mask" "F.Paste")
			(net "M_D_CPU1_SB_DQ<4>")
		)
		(pad "CF61" smd circle
			(at 21.470112 18.18005 180)
			(size 0.450088 0.450088)
			(layers "F.Cu" "F.Mask" "F.Paste")
			(net "GND")
		)
	)
)
